(kicad_pcb
	(version 20260206)
	(generator "pcbnew")
	(generator_version "10.0")
	(general
		(thickness 1.6)
		(legacy_teardrops no)
	)
	(paper "A4")
	(title_block
		(title "Bryce Canyon_F.DPB_16315-1-OCP.brd")
		(comment 1 "Bryce Canyon / footprints 916-923 of 2223")
	)
	(layers
		(0 "F.Cu" signal "TOP")
		(4 "In1.Cu" signal "L2GND")
		(6 "In2.Cu" signal "L3")
		(8 "In3.Cu" signal "L4GND")
		(10 "In4.Cu" signal "L5")
		(12 "In5.Cu" signal "L6VCC")
		(14 "In6.Cu" signal "L7VCC")
		(16 "In7.Cu" signal "L8")
		(18 "In8.Cu" signal "L9GND")
		(20 "In9.Cu" signal "L10")
		(22 "In10.Cu" signal "L11GND")
		(2 "B.Cu" signal "BOTTOM")
		(9 "F.Adhes" user "F.Adhesive")
		(11 "B.Adhes" user "B.Adhesive")
		(13 "F.Paste" user "Package Geometry/Pastemask Top")
		(15 "B.Paste" user "Package Geometry/Pastemask Bottom")
		(5 "F.SilkS" user "Ref Des/Silkscreen Top")
		(7 "B.SilkS" user "Ref Des/Silkscreen Bottom")
		(1 "F.Mask" user "Board Geometry/Soldermask Top")
		(3 "B.Mask" user "Board Geometry/Soldermask Bottom")
		(17 "Dwgs.User" user "User.Drawings")
		(19 "Cmts.User" user "User.Comments")
		(21 "Eco1.User" user "User.Eco1")
		(23 "Eco2.User" user "User.Eco2")
		(25 "Edge.Cuts" user "Board Geometry/Outline")
		(27 "Margin" user)
		(31 "F.CrtYd" user "Package Geometry/Place Bound Top")
		(29 "B.CrtYd" user "Package Geometry/Place Bound Bottom")
		(35 "F.Fab" user "Ref Des/Assembly Top")
		(33 "B.Fab" user "Ref Des/Assembly Bottom")
	)
	(footprint ""
		(layer "F.Cu")
		(at 64.013334 -158.660592 90)
		(property "Reference" "C208"
			(at 0 0 90)
			(layer "F.SilkS")
			(hide yes)
			(effects
				(font
					(size 1.27 1.27)
				)
			)
		)
		(property "Value" "SCD01U16V1KX-GP"
			(at -2.8321 -1.7399 90)
			(unlocked yes)
			(layer "F.Fab")
			(hide yes)
			(effects
				(font
					(size 1.016 1.016)
					(thickness 0.1524)
				)
			)
		)
		(property "Device Type" "C0201H13"
			(at -2.8321 -3.2639 90)
			(unlocked yes)
			(layer "F.Fab")
			(hide yes)
			(effects
				(font
					(size 1.016 1.016)
					(thickness 0.1524)
				)
			)
		)
		(duplicate_pad_numbers_are_jumpers no)
		(fp_rect
			(start -0.2794 0.6477)
			(end 0.2794 -0.6477)
			(stroke
				(width 0)
				(type default)
			)
			(fill no)
			(layer "F.CrtYd")
		)
		(fp_rect
			(start -0.2794 0.6477)
			(end 0.2794 -0.6477)
			(stroke
				(width 0)
				(type default)
			)
			(fill no)
			(layer "F.Fab")
		)
		(pad "1" smd custom
			(at 0 -0.2794 90)
			(size 0.0762 0.0762)
			(layers "F.Cu" "F.Mask" "F.Paste")
			(net "SAS_HDD_RX_P13")
			(options
				(clearance outline)
				(anchor circle)
			)
			(primitives
				(gr_poly
					(pts
						(arc
							(start 0.1524 -0.127)
							(mid 0.137521 -0.162921)
							(end 0.1016 -0.1778)
						)
						(arc
							(start -0.1016 -0.1778)
							(mid -0.137521 -0.162921)
							(end -0.1524 -0.127)
						)
						(arc
							(start -0.1524 0.127)
							(mid -0.137521 0.162921)
							(end -0.1016 0.1778)
						)
						(arc
							(start 0.1016 0.1778)
							(mid 0.137521 0.162921)
							(end 0.1524 0.127)
						)
					)
					(width 0)
					(fill yes)
				)
			)
		)
		(pad "2" smd custom
			(at 0 0.2794 90)
			(size 0.0762 0.0762)
			(layers "F.Cu" "F.Mask" "F.Paste")
			(net "PHY_SCC_A_TO_DRV_A_13_DP")
			(options
				(clearance outline)
				(anchor circle)
			)
			(primitives
				(gr_poly
					(pts
						(arc
							(start 0.1524 -0.127)
							(mid 0.137521 -0.162921)
							(end 0.1016 -0.1778)
						)
						(arc
							(start -0.1016 -0.1778)
							(mid -0.137521 -0.162921)
							(end -0.1524 -0.127)
						)
						(arc
							(start -0.1524 0.127)
							(mid -0.137521 0.162921)
							(end -0.1016 0.1778)
						)
						(arc
							(start 0.1016 0.1778)
							(mid 0.137521 0.162921)
							(end 0.1524 0.127)
						)
					)
					(width 0)
					(fill yes)
				)
			)
		)
	)
	(footprint ""
		(layer "F.Cu")
		(at 14.842998 -54.523894 90)
		(property "Reference" "C361"
			(at 0 0 90)
			(layer "F.SilkS")
			(hide yes)
			(effects
				(font
					(size 1.27 1.27)
				)
			)
		)
		(property "Value" "SCD033U25V2KX-GP"
			(at 1.1811 -2.7051 90)
			(unlocked yes)
			(layer "F.Fab")
			(hide yes)
			(effects
				(font
					(size 1.016 1.016)
					(thickness 0.1524)
				)
			)
		)
		(property "Device Type" "C402H22"
			(at 1.1811 -4.2291 90)
			(unlocked yes)
			(layer "F.Fab")
			(hide yes)
			(effects
				(font
					(size 1.016 1.016)
					(thickness 0.1524)
				)
			)
		)
		(duplicate_pad_numbers_are_jumpers no)
		(fp_rect
			(start -0.4318 0.9525)
			(end 0.4318 -0.9525)
			(stroke
				(width 0)
				(type default)
			)
			(fill no)
			(layer "F.CrtYd")
		)
		(fp_rect
			(start -0.4318 0.9525)
			(end 0.4318 -0.9525)
			(stroke
				(width 0)
				(type default)
			)
			(fill no)
			(layer "F.Fab")
		)
		(pad "1" smd custom
			(at 0 -0.4445 90)
			(size 0.1524 0.1524)
			(layers "F.Cu" "F.Mask" "F.Paste")
			(net "P12V_A")
			(options
				(clearance outline)
				(anchor circle)
			)
			(primitives
				(gr_poly
					(pts
						(arc
							(start 0.3048 -0.2032)
							(mid 0.275042 -0.275042)
							(end 0.2032 -0.3048)
						)
						(arc
							(start -0.2032 -0.3048)
							(mid -0.275042 -0.275042)
							(end -0.3048 -0.2032)
						)
						(arc
							(start -0.3048 0.2032)
							(mid -0.275042 0.275042)
							(end -0.2032 0.3048)
						)
						(arc
							(start 0.2032 0.3048)
							(mid 0.275042 0.275042)
							(end 0.3048 0.2032)
						)
					)
					(width 0)
					(fill yes)
				)
			)
		)
		(pad "2" smd custom
			(at 0 0.4445 90)
			(size 0.1524 0.1524)
			(layers "F.Cu" "F.Mask" "F.Paste")
			(net "SW_HDD_N24")
			(options
				(clearance outline)
				(anchor circle)
			)
			(primitives
				(gr_poly
					(pts
						(arc
							(start 0.3048 -0.2032)
							(mid 0.275042 -0.275042)
							(end 0.2032 -0.3048)
						)
						(arc
							(start -0.2032 -0.3048)
							(mid -0.275042 -0.275042)
							(end -0.3048 -0.2032)
						)
						(arc
							(start -0.3048 0.2032)
							(mid -0.275042 0.275042)
							(end -0.2032 0.3048)
						)
						(arc
							(start 0.2032 0.3048)
							(mid 0.275042 0.275042)
							(end 0.3048 0.2032)
						)
					)
					(width 0)
					(fill yes)
				)
			)
		)
	)
	(footprint ""
		(layer "F.Cu")
		(at 471.603324 -282.776676 -90)
		(property "Reference" "R398"
			(at 0 0 270)
			(layer "F.SilkS")
			(hide yes)
			(effects
				(font
					(size 1.27 1.27)
				)
			)
		)
		(property "Value" "300KR2F-GP"
			(at 0.064008 -3.993896 270)
			(unlocked yes)
			(layer "F.Fab")
			(hide yes)
			(effects
				(font
					(size 1.016 1.016)
					(thickness 0.1524)
				)
			)
		)
		(property "Device Type" "R402H16"
			(at 0.064008 -5.517896 270)
			(unlocked yes)
			(layer "F.Fab")
			(hide yes)
			(effects
				(font
					(size 1.016 1.016)
					(thickness 0.1524)
				)
			)
		)
		(duplicate_pad_numbers_are_jumpers no)
		(fp_line
			(start -0.508 -0.9398)
			(end -0.508 0.9398)
			(stroke
				(width 0.1524)
				(type default)
			)
			(layer "F.SilkS")
		)
		(fp_line
			(start 0.508 -0.9398)
			(end -0.508 -0.9398)
			(stroke
				(width 0.1524)
				(type default)
			)
			(layer "F.SilkS")
		)
		(fp_rect
			(start -0.508 0.9398)
			(end 0.508 -0.9398)
			(stroke
				(width 0)
				(type default)
			)
			(fill no)
			(layer "F.CrtYd")
		)
		(fp_rect
			(start -0.508 0.9398)
			(end 0.508 -0.9398)
			(stroke
				(width 0)
				(type default)
			)
			(fill no)
			(layer "F.Fab")
		)
		(pad "1" smd custom
			(at 0 -0.4445 270)
			(size 0.1397 0.1397)
			(layers "F.Cu" "F.Mask" "F.Paste")
			(net "SW_HDD_N11")
			(options
				(clearance outline)
				(anchor circle)
			)
			(primitives
				(gr_poly
					(pts
						(arc
							(start -0.1778 -0.2794)
							(mid -0.249642 -0.249642)
							(end -0.2794 -0.1778)
						)
						(arc
							(start -0.2794 0.1778)
							(mid -0.249642 0.249642)
							(end -0.1778 0.2794)
						)
						(arc
							(start 0.1778 0.2794)
							(mid 0.249642 0.249642)
							(end 0.2794 0.1778)
						)
						(arc
							(start 0.2794 -0.1778)
							(mid 0.249642 -0.249642)
							(end 0.1778 -0.2794)
						)
					)
					(width 0)
					(fill yes)
				)
			)
		)
		(pad "2" smd custom
			(at 0 0.4445 270)
			(size 0.1397 0.1397)
			(layers "F.Cu" "F.Mask" "F.Paste")
			(net "P12V_A")
			(options
				(clearance outline)
				(anchor circle)
			)
			(primitives
				(gr_poly
					(pts
						(arc
							(start -0.1778 -0.2794)
							(mid -0.249642 -0.249642)
							(end -0.2794 -0.1778)
						)
						(arc
							(start -0.2794 0.1778)
							(mid -0.249642 0.249642)
							(end -0.1778 0.2794)
						)
						(arc
							(start 0.1778 0.2794)
							(mid 0.249642 0.249642)
							(end 0.2794 0.1778)
						)
						(arc
							(start 0.2794 -0.1778)
							(mid 0.249642 -0.249642)
							(end 0.1778 -0.2794)
						)
					)
					(width 0)
					(fill yes)
				)
			)
		)
	)
	(footprint ""
		(layer "F.Cu")
		(at 331.47 -303.954942 180)
		(property "Reference" "C122"
			(at 0 0 180)
			(layer "F.SilkS")
			(hide yes)
			(effects
				(font
					(size 1.27 1.27)
				)
			)
		)
		(property "Value" "SC4D7U25V5KX-1-GP"
			(at -0.0762 -6.1214 180)
			(unlocked yes)
			(layer "F.Fab")
			(hide yes)
			(effects
				(font
					(size 1.016 1.016)
					(thickness 0.1524)
				)
			)
		)
		(property "Device Type" "C805H58"
			(at -0.0762 -8.1534 180)
			(unlocked yes)
			(layer "F.Fab")
			(hide yes)
			(effects
				(font
					(size 1.016 1.016)
					(thickness 0.1524)
				)
			)
		)
		(duplicate_pad_numbers_are_jumpers no)
		(fp_line
			(start 0.635 0)
			(end -0.635 0)
			(stroke
				(width 0.508)
				(type default)
			)
			(layer "F.SilkS")
		)
		(fp_rect
			(start -0.9652 1.778)
			(end 0.9652 -1.778)
			(stroke
				(width 0)
				(type default)
			)
			(fill no)
			(layer "F.CrtYd")
		)
		(fp_poly
			(pts
				(xy -0.9652 -1.778) (xy 0.9652 -1.778) (xy 0.9652 1.778) (xy -0.9652 1.778)
			)
			(stroke
				(width 0)
				(type default)
			)
			(fill no)
			(layer "F.Fab")
		)
		(pad "1" smd rect
			(at 0 -0.9652 180)
			(size 1.397 1.143)
			(layers "F.Cu" "F.Mask" "F.Paste")
			(net "P12V_HDD6")
		)
		(pad "2" smd rect
			(at 0 0.9652 180)
			(size 1.397 1.143)
			(layers "F.Cu" "F.Mask" "F.Paste")
			(net "GND")
		)
	)
	(footprint ""
		(layer "F.Cu")
		(at 321.634612 -43.660568 -90)
		(property "Reference" "C429"
			(at 0 0 270)
			(layer "F.SilkS")
			(hide yes)
			(effects
				(font
					(size 1.27 1.27)
				)
			)
		)
		(property "Value" "SCD01U16V1KX-GP"
			(at -2.8321 -1.7399 270)
			(unlocked yes)
			(layer "F.Fab")
			(hide yes)
			(effects
				(font
					(size 1.016 1.016)
					(thickness 0.1524)
				)
			)
		)
		(property "Device Type" "C0201H13"
			(at -2.8321 -3.2639 270)
			(unlocked yes)
			(layer "F.Fab")
			(hide yes)
			(effects
				(font
					(size 1.016 1.016)
					(thickness 0.1524)
				)
			)
		)
		(duplicate_pad_numbers_are_jumpers no)
		(fp_rect
			(start -0.2794 0.6477)
			(end 0.2794 -0.6477)
			(stroke
				(width 0)
				(type default)
			)
			(fill no)
			(layer "F.CrtYd")
		)
		(fp_rect
			(start -0.2794 0.6477)
			(end 0.2794 -0.6477)
			(stroke
				(width 0)
				(type default)
			)
			(fill no)
			(layer "F.Fab")
		)
		(pad "1" smd custom
			(at 0 -0.2794 270)
			(size 0.0762 0.0762)
			(layers "F.Cu" "F.Mask" "F.Paste")
			(net "SAS_HDD_RX_P30")
			(options
				(clearance outline)
				(anchor circle)
			)
			(primitives
				(gr_poly
					(pts
						(arc
							(start 0.1524 -0.127)
							(mid 0.137521 -0.162921)
							(end 0.1016 -0.1778)
						)
						(arc
							(start -0.1016 -0.1778)
							(mid -0.137521 -0.162921)
							(end -0.1524 -0.127)
						)
						(arc
							(start -0.1524 0.127)
							(mid -0.137521 0.162921)
							(end -0.1016 0.1778)
						)
						(arc
							(start 0.1016 0.1778)
							(mid 0.137521 0.162921)
							(end 0.1524 0.127)
						)
					)
					(width 0)
					(fill yes)
				)
			)
		)
		(pad "2" smd custom
			(at 0 0.2794 270)
			(size 0.0762 0.0762)
			(layers "F.Cu" "F.Mask" "F.Paste")
			(net "PHY_SCC_A_TO_DRV_A_30_DP")
			(options
				(clearance outline)
				(anchor circle)
			)
			(primitives
				(gr_poly
					(pts
						(arc
							(start 0.1524 -0.127)
							(mid 0.137521 -0.162921)
							(end 0.1016 -0.1778)
						)
						(arc
							(start -0.1016 -0.1778)
							(mid -0.137521 -0.162921)
							(end -0.1524 -0.127)
						)
						(arc
							(start -0.1524 0.127)
							(mid -0.137521 0.162921)
							(end -0.1016 0.1778)
						)
						(arc
							(start 0.1016 0.1778)
							(mid 0.137521 0.162921)
							(end 0.1524 0.127)
						)
					)
					(width 0)
					(fill yes)
				)
			)
		)
	)
	(footprint ""
		(layer "F.Cu")
		(at 351.539302 -273.940016 90)
		(property "Reference" "VIA2"
			(at 0 0 90)
			(layer "F.SilkS")
			(hide yes)
			(effects
				(font
					(size 1.27 1.27)
				)
			)
		)
		(property "Value" "100OHM-8L-1D6MM-L18L16-GP"
			(at -3.7211 -4.5085 90)
			(unlocked yes)
			(layer "F.Fab")
			(hide yes)
			(effects
				(font
					(size 1.016 1.016)
					(thickness 0.1524)
				)
			)
		)
		(property "Device Type" "VIA-PCIE-4P-394076"
			(at -3.7211 -6.0325 90)
			(unlocked yes)
			(layer "F.Fab")
			(hide yes)
			(effects
				(font
					(size 1.016 1.016)
					(thickness 0.1524)
				)
			)
		)
		(duplicate_pad_numbers_are_jumpers no)
		(fp_rect
			(start -1.9685 0.381)
			(end 1.9685 -0.381)
			(stroke
				(width 0)
				(type default)
			)
			(fill no)
			(layer "F.CrtYd")
		)
		(fp_rect
			(start -1.9685 0.381)
			(end 1.9685 -0.381)
			(stroke
				(width 0)
				(type default)
			)
			(fill no)
			(layer "F.Fab")
		)
		(pad "1" thru_hole circle
			(at -1.5875 0 90)
			(size 0.508 0.508)
			(drill 0.254)
			(layers "*.Cu" "*.Mask")
			(remove_unused_layers no)
			(net "GND")
			(clearance 0.127)
			(thermal_gap 0.127)
		)
		(pad "2" thru_hole circle
			(at -0.5715 0 90)
			(size 0.508 0.508)
			(drill 0.254)
			(layers "*.Cu" "*.Mask")
			(remove_unused_layers no)
			(net "PHY_SCC_A_TO_DRV_A_7_DP")
			(clearance 0.127)
			(thermal_gap 0.127)
		)
		(pad "3" thru_hole circle
			(at 0.5715 0 90)
			(size 0.508 0.508)
			(drill 0.254)
			(layers "*.Cu" "*.Mask")
			(remove_unused_layers no)
			(net "PHY_SCC_A_TO_DRV_A_7_DN")
			(clearance 0.127)
			(thermal_gap 0.127)
		)
		(pad "4" thru_hole circle
			(at 1.5875 0 90)
			(size 0.508 0.508)
			(drill 0.254)
			(layers "*.Cu" "*.Mask")
			(remove_unused_layers no)
			(net "GND")
			(clearance 0.127)
			(thermal_gap 0.127)
		)
	)
	(footprint ""
		(layer "F.Cu")
		(at 176.983898 -148.94433)
		(property "Reference" "C551"
			(at 0 0 0)
			(layer "F.SilkS")
			(hide yes)
			(effects
				(font
					(size 1.27 1.27)
				)
			)
		)
		(property "Value" "SCD1U25V2KX-2-GP"
			(at 1.1811 -2.7051 0)
			(unlocked yes)
			(layer "F.Fab")
			(hide yes)
			(effects
				(font
					(size 1.016 1.016)
					(thickness 0.1524)
				)
			)
		)
		(property "Device Type" "C402H22"
			(at 1.1811 -4.2291 0)
			(unlocked yes)
			(layer "F.Fab")
			(hide yes)
			(effects
				(font
					(size 1.016 1.016)
					(thickness 0.1524)
				)
			)
		)
		(duplicate_pad_numbers_are_jumpers no)
		(fp_rect
			(start -0.4318 0.9525)
			(end 0.4318 -0.9525)
			(stroke
				(width 0)
				(type default)
			)
			(fill no)
			(layer "F.CrtYd")
		)
		(fp_rect
			(start -0.4318 0.9525)
			(end 0.4318 -0.9525)
			(stroke
				(width 0)
				(type default)
			)
			(fill no)
			(layer "F.Fab")
		)
		(pad "1" smd custom
			(at 0 -0.4445)
			(size 0.1524 0.1524)
			(layers "F.Cu" "F.Mask" "F.Paste")
			(net "P12V_A")
			(options
				(clearance outline)
				(anchor circle)
			)
			(primitives
				(gr_poly
					(pts
						(arc
							(start 0.3048 -0.2032)
							(mid 0.275042 -0.275042)
							(end 0.2032 -0.3048)
						)
						(arc
							(start -0.2032 -0.3048)
							(mid -0.275042 -0.275042)
							(end -0.3048 -0.2032)
						)
						(arc
							(start -0.3048 0.2032)
							(mid -0.275042 0.275042)
							(end -0.2032 0.3048)
						)
						(arc
							(start 0.2032 0.3048)
							(mid 0.275042 0.275042)
							(end 0.3048 0.2032)
						)
					)
					(width 0)
					(fill yes)
				)
			)
		)
		(pad "2" smd custom
			(at 0 0.4445)
			(size 0.1524 0.1524)
			(layers "F.Cu" "F.Mask" "F.Paste")
			(net "GND")
			(options
				(clearance outline)
				(anchor circle)
			)
			(primitives
				(gr_poly
					(pts
						(arc
							(start 0.3048 -0.2032)
							(mid 0.275042 -0.275042)
							(end 0.2032 -0.3048)
						)
						(arc
							(start -0.2032 -0.3048)
							(mid -0.275042 -0.275042)
							(end -0.3048 -0.2032)
						)
						(arc
							(start -0.3048 0.2032)
							(mid -0.275042 0.275042)
							(end -0.2032 0.3048)
						)
						(arc
							(start 0.2032 0.3048)
							(mid 0.275042 0.275042)
							(end 0.3048 0.2032)
						)
					)
					(width 0)
					(fill yes)
				)
			)
		)
	)
	(footprint ""
		(layer "F.Cu")
		(at 77.942948 -168.482518 -90)
		(property "Reference" "R467"
			(at 0 0 270)
			(layer "F.SilkS")
			(hide yes)
			(effects
				(font
					(size 1.27 1.27)
				)
			)
		)
		(property "Value" "300KR2F-GP"
			(at 0.064008 -3.993896 270)
			(unlocked yes)
			(layer "F.Fab")
			(hide yes)
			(effects
				(font
					(size 1.016 1.016)
					(thickness 0.1524)
				)
			)
		)
		(property "Device Type" "R402H16"
			(at 0.064008 -5.517896 270)
			(unlocked yes)
			(layer "F.Fab")
			(hide yes)
			(effects
				(font
					(size 1.016 1.016)
					(thickness 0.1524)
				)
			)
		)
		(duplicate_pad_numbers_are_jumpers no)
		(fp_line
			(start -0.508 -0.9398)
			(end -0.508 0.9398)
			(stroke
				(width 0.1524)
				(type default)
			)
			(layer "F.SilkS")
		)
		(fp_line
			(start 0.508 -0.9398)
			(end -0.508 -0.9398)
			(stroke
				(width 0.1524)
				(type default)
			)
			(layer "F.SilkS")
		)
		(fp_rect
			(start -0.508 0.9398)
			(end 0.508 -0.9398)
			(stroke
				(width 0)
				(type default)
			)
			(fill no)
			(layer "F.CrtYd")
		)
		(fp_rect
			(start -0.508 0.9398)
			(end 0.508 -0.9398)
			(stroke
				(width 0)
				(type default)
			)
			(fill no)
			(layer "F.Fab")
		)
		(pad "1" smd custom
			(at 0 -0.4445 270)
			(size 0.1397 0.1397)
			(layers "F.Cu" "F.Mask" "F.Paste")
			(net "SW_HDD_N14")
			(options
				(clearance outline)
				(anchor circle)
			)
			(primitives
				(gr_poly
					(pts
						(arc
							(start -0.1778 -0.2794)
							(mid -0.249642 -0.249642)
							(end -0.2794 -0.1778)
						)
						(arc
							(start -0.2794 0.1778)
							(mid -0.249642 0.249642)
							(end -0.1778 0.2794)
						)
						(arc
							(start 0.1778 0.2794)
							(mid 0.249642 0.249642)
							(end 0.2794 0.1778)
						)
						(arc
							(start 0.2794 -0.1778)
							(mid 0.249642 -0.249642)
							(end 0.1778 -0.2794)
						)
					)
					(width 0)
					(fill yes)
				)
			)
		)
		(pad "2" smd custom
			(at 0 0.4445 270)
			(size 0.1397 0.1397)
			(layers "F.Cu" "F.Mask" "F.Paste")
			(net "P12V_A")
			(options
				(clearance outline)
				(anchor circle)
			)
			(primitives
				(gr_poly
					(pts
						(arc
							(start -0.1778 -0.2794)
							(mid -0.249642 -0.249642)
							(end -0.2794 -0.1778)
						)
						(arc
							(start -0.2794 0.1778)
							(mid -0.249642 0.249642)
							(end -0.1778 0.2794)
						)
						(arc
							(start 0.1778 0.2794)
							(mid 0.249642 0.249642)
							(end 0.2794 0.1778)
						)
						(arc
							(start 0.2794 -0.1778)
							(mid 0.249642 -0.249642)
							(end 0.1778 -0.2794)
						)
					)
					(width 0)
					(fill yes)
				)
			)
		)
	)
)
